# S9S_MB_2U (Grand Teton) — schematic netlist excerpt (pin names and nets, part order shuffled) for the footprints in the layout excerpt that follows; sources: Cadence DE-HDL packaged netlist, KiCad conversion of 03242023_DA0F0TMBIJ0_F0T_Motherboard_J_brd_V01_OCP.brd

R4709  Q_RES  0 5% CHIP  pkg 0402LF  page 242 : A = P12V_SCM_FLTB_N ; B = P12V_SCM_FAULT_R_N
R2588  Q_RES  22 1% CHIP  pkg 0402LF  page 301 : A = HSC_FAULT ; B = IRQ_HSC_FAULT_N

(kicad_pcb
	(version 20260206)
	(generator "pcbnew")
	(generator_version "10.0")
	(general
		(thickness 1.6)
		(legacy_teardrops no)
	)
	(paper "A4")
	(title_block
		(title "03242023_DA0F0TMBIJ0_F0T_Motherboard_J_brd_V01_OCP.brd")
		(comment 1 "Grand Teton / footprints 394-395 of 6105")
	)
	(layers
		(0 "F.Cu" signal "TOP")
		(4 "In1.Cu" signal "GND")
		(6 "In2.Cu" signal "IN1")
		(8 "In3.Cu" signal "GND1")
		(10 "In4.Cu" signal "IN2")
		(12 "In5.Cu" signal "GND2")
		(14 "In6.Cu" signal "IN3")
		(16 "In7.Cu" signal "GND3")
		(18 "In8.Cu" signal "VCC")
		(20 "In9.Cu" signal "VCC1")
		(22 "In10.Cu" signal "GND4")
		(24 "In11.Cu" signal "IN4")
		(26 "In12.Cu" signal "GND5")
		(28 "In13.Cu" signal "IN5")
		(30 "In14.Cu" signal "GND6")
		(32 "In15.Cu" signal "IN6")
		(34 "In16.Cu" signal "GND7")
		(2 "B.Cu" signal "BOTTOM")
		(9 "F.Adhes" user "F.Adhesive")
		(11 "B.Adhes" user "B.Adhesive")
		(13 "F.Paste" user "Package Geometry/Pastemask Top")
		(15 "B.Paste" user "Package Geometry/Pastemask Bottom")
		(5 "F.SilkS" user "Ref Des/Silkscreen Top")
		(7 "B.SilkS" user "Ref Des/Silkscreen Bottom")
		(1 "F.Mask" user "Board Geometry/Soldermask Top")
		(3 "B.Mask" user "Board Geometry/Soldermask Bottom")
		(17 "Dwgs.User" user "User.Drawings")
		(19 "Cmts.User" user "User.Comments")
		(21 "Eco1.User" user "User.Eco1")
		(23 "Eco2.User" user "User.Eco2")
		(25 "Edge.Cuts" user "Board Geometry/Outline")
		(27 "Margin" user)
		(31 "F.CrtYd" user "Package Geometry/Place Bound Top")
		(29 "B.CrtYd" user "Package Geometry/Place Bound Bottom")
		(35 "F.Fab" user "Ref Des/Assembly Top")
		(33 "B.Fab" user "Ref Des/Assembly Bottom")
	)
	(footprint ""
		(layer "F.Cu")
		(at 173.216062 -31.34868 180)
		(property "Reference" "R4709"
			(at 0 0 180)
			(layer "F.SilkS")
			(hide yes)
			(effects
				(font
					(size 1.27 1.27)
				)
			)
		)
		(property "Value" ""
			(at 0 0 180)
			(layer "F.Fab")
			(effects
				(font
					(size 1.27 1.27)
				)
			)
		)
		(duplicate_pad_numbers_are_jumpers no)
		(fp_line
			(start 0.7874 0.4064)
			(end -0.7874 0.4064)
			(stroke
				(width 0.1524)
				(type default)
			)
			(layer "F.SilkS")
		)
		(fp_line
			(start 0.7874 -0.4064)
			(end 0.7874 0.4064)
			(stroke
				(width 0.1524)
				(type default)
			)
			(layer "F.SilkS")
		)
		(fp_line
			(start -0.7874 0.4064)
			(end -0.7874 -0.4064)
			(stroke
				(width 0.1524)
				(type default)
			)
			(layer "F.SilkS")
		)
		(fp_line
			(start -0.7874 -0.4064)
			(end 0.7874 -0.4064)
			(stroke
				(width 0.1524)
				(type default)
			)
			(layer "F.SilkS")
		)
		(fp_line
			(start 0.67945 0.3048)
			(end 0.120396 0.3048)
			(stroke
				(width 0.1)
				(type default)
			)
			(layer "F.Fab")
		)
		(fp_line
			(start 0.67945 -0.3048)
			(end 0.67945 0.3048)
			(stroke
				(width 0.1)
				(type default)
			)
			(layer "F.Fab")
		)
		(fp_line
			(start 0.12065 -0.2794)
			(end 0.12065 -0.3048)
			(stroke
				(width 0.1)
				(type default)
			)
			(layer "F.Fab")
		)
		(fp_line
			(start 0.12065 -0.3048)
			(end 0.67945 -0.3048)
			(stroke
				(width 0.1)
				(type default)
			)
			(layer "F.Fab")
		)
		(fp_line
			(start 0.120396 0.3048)
			(end 0.120396 0.2794)
			(stroke
				(width 0.1)
				(type default)
			)
			(layer "F.Fab")
		)
		(fp_line
			(start 0.120396 0.2794)
			(end -0.12065 0.2794)
			(stroke
				(width 0.1)
				(type default)
			)
			(layer "F.Fab")
		)
		(fp_line
			(start -0.12065 0.3048)
			(end -0.67945 0.3048)
			(stroke
				(width 0.1)
				(type default)
			)
			(layer "F.Fab")
		)
		(fp_line
			(start -0.12065 0.2794)
			(end -0.12065 0.3048)
			(stroke
				(width 0.1)
				(type default)
			)
			(layer "F.Fab")
		)
		(fp_line
			(start -0.12065 -0.2794)
			(end 0.12065 -0.2794)
			(stroke
				(width 0.1)
				(type default)
			)
			(layer "F.Fab")
		)
		(fp_line
			(start -0.12065 -0.305054)
			(end -0.12065 -0.2794)
			(stroke
				(width 0.1)
				(type default)
			)
			(layer "F.Fab")
		)
		(fp_line
			(start -0.67945 0.3048)
			(end -0.67945 -0.305054)
			(stroke
				(width 0.1)
				(type default)
			)
			(layer "F.Fab")
		)
		(fp_line
			(start -0.67945 -0.305054)
			(end -0.12065 -0.305054)
			(stroke
				(width 0.1)
				(type default)
			)
			(layer "F.Fab")
		)
		(pad "1" smd circle
			(at -0.40005 0 180)
			(size 0 0)
			(layers "F.Cu" "F.Mask" "F.Paste")
			(net "P12V_SCM_FLTB_N")
		)
		(pad "2" smd circle
			(at 0.40005 0 180)
			(size 0 0)
			(layers "F.Cu" "F.Mask" "F.Paste")
			(net "P12V_SCM_FAULT_R_N")
		)
	)
	(footprint ""
		(layer "F.Cu")
		(at 192.052448 -403.144482)
		(property "Reference" "R2588"
			(at 0 0 0)
			(layer "F.SilkS")
			(hide yes)
			(effects
				(font
					(size 1.27 1.27)
				)
			)
		)
		(property "Value" ""
			(at 0 0 0)
			(layer "F.Fab")
			(effects
				(font
					(size 1.27 1.27)
				)
			)
		)
		(duplicate_pad_numbers_are_jumpers no)
		(fp_line
			(start -0.7874 -0.4064)
			(end 0.7874 -0.4064)
			(stroke
				(width 0.1524)
				(type default)
			)
			(layer "F.SilkS")
		)
		(fp_line
			(start -0.7874 0.4064)
			(end -0.7874 -0.4064)
			(stroke
				(width 0.1524)
				(type default)
			)
			(layer "F.SilkS")
		)
		(fp_line
			(start 0.7874 -0.4064)
			(end 0.7874 0.4064)
			(stroke
				(width 0.1524)
				(type default)
			)
			(layer "F.SilkS")
		)
		(fp_line
			(start 0.7874 0.4064)
			(end -0.7874 0.4064)
			(stroke
				(width 0.1524)
				(type default)
			)
			(layer "F.SilkS")
		)
		(fp_line
			(start -0.67945 -0.305054)
			(end -0.12065 -0.305054)
			(stroke
				(width 0.1)
				(type default)
			)
			(layer "F.Fab")
		)
		(fp_line
			(start -0.67945 0.3048)
			(end -0.67945 -0.305054)
			(stroke
				(width 0.1)
				(type default)
			)
			(layer "F.Fab")
		)
		(fp_line
			(start -0.12065 -0.305054)
			(end -0.12065 -0.2794)
			(stroke
				(width 0.1)
				(type default)
			)
			(layer "F.Fab")
		)
		(fp_line
			(start -0.12065 -0.2794)
			(end 0.12065 -0.2794)
			(stroke
				(width 0.1)
				(type default)
			)
			(layer "F.Fab")
		)
		(fp_line
			(start -0.12065 0.2794)
			(end -0.12065 0.3048)
			(stroke
				(width 0.1)
				(type default)
			)
			(layer "F.Fab")
		)
		(fp_line
			(start -0.12065 0.3048)
			(end -0.67945 0.3048)
			(stroke
				(width 0.1)
				(type default)
			)
			(layer "F.Fab")
		)
		(fp_line
			(start 0.120396 0.2794)
			(end -0.12065 0.2794)
			(stroke
				(width 0.1)
				(type default)
			)
			(layer "F.Fab")
		)
		(fp_line
			(start 0.120396 0.3048)
			(end 0.120396 0.2794)
			(stroke
				(width 0.1)
				(type default)
			)
			(layer "F.Fab")
		)
		(fp_line
			(start 0.12065 -0.3048)
			(end 0.67945 -0.3048)
			(stroke
				(width 0.1)
				(type default)
			)
			(layer "F.Fab")
		)
		(fp_line
			(start 0.12065 -0.2794)
			(end 0.12065 -0.3048)
			(stroke
				(width 0.1)
				(type default)
			)
			(layer "F.Fab")
		)
		(fp_line
			(start 0.67945 -0.3048)
			(end 0.67945 0.3048)
			(stroke
				(width 0.1)
				(type default)
			)
			(layer "F.Fab")
		)
		(fp_line
			(start 0.67945 0.3048)
			(end 0.120396 0.3048)
			(stroke
				(width 0.1)
				(type default)
			)
			(layer "F.Fab")
		)
		(pad "1" smd circle
			(at -0.40005 0)
			(size 0 0)
			(layers "F.Cu" "F.Mask" "F.Paste")
			(net "HSC_FAULT")
		)
		(pad "2" smd circle
			(at 0.40005 0)
			(size 0 0)
			(layers "F.Cu" "F.Mask" "F.Paste")
			(net "IRQ_HSC_FAULT_N")
		)
	)
)
